# S9S_MB_2U (Grand Teton) — schematic netlist excerpt (pin names and nets, part order shuffled) for the footprints in the layout excerpt that follows; sources: Cadence DE-HDL packaged netlist, KiCad conversion of 03242023_DA0F0TMBIJ0_F0T_Motherboard_J_brd_V01_OCP.brd

R1492  Q_RES  10K 1% CHIP  pkg 0402LF  page 220 : A = FM_DIS_PS_PWROK_DLY ; B = P3V3_AUX
PC1242_P1_1  Q_CAP  2.2UF 10V 10% X6S  pkg C0402  page 289 : A = PVCCFA_EHV_FIVRA_CPU1_PVCC1 ; B = GND

(kicad_pcb
	(version 20260206)
	(generator "pcbnew")
	(generator_version "10.0")
	(general
		(thickness 1.6)
		(legacy_teardrops no)
	)
	(paper "A4")
	(title_block
		(title "03242023_DA0F0TMBIJ0_F0T_Motherboard_J_brd_V01_OCP.brd")
		(comment 1 "Grand Teton / footprints 1677-1678 of 6105")
	)
	(layers
		(0 "F.Cu" signal "TOP")
		(4 "In1.Cu" signal "GND")
		(6 "In2.Cu" signal "IN1")
		(8 "In3.Cu" signal "GND1")
		(10 "In4.Cu" signal "IN2")
		(12 "In5.Cu" signal "GND2")
		(14 "In6.Cu" signal "IN3")
		(16 "In7.Cu" signal "GND3")
		(18 "In8.Cu" signal "VCC")
		(20 "In9.Cu" signal "VCC1")
		(22 "In10.Cu" signal "GND4")
		(24 "In11.Cu" signal "IN4")
		(26 "In12.Cu" signal "GND5")
		(28 "In13.Cu" signal "IN5")
		(30 "In14.Cu" signal "GND6")
		(32 "In15.Cu" signal "IN6")
		(34 "In16.Cu" signal "GND7")
		(2 "B.Cu" signal "BOTTOM")
		(9 "F.Adhes" user "F.Adhesive")
		(11 "B.Adhes" user "B.Adhesive")
		(13 "F.Paste" user "Package Geometry/Pastemask Top")
		(15 "B.Paste" user "Package Geometry/Pastemask Bottom")
		(5 "F.SilkS" user "Ref Des/Silkscreen Top")
		(7 "B.SilkS" user "Ref Des/Silkscreen Bottom")
		(1 "F.Mask" user "Board Geometry/Soldermask Top")
		(3 "B.Mask" user "Board Geometry/Soldermask Bottom")
		(17 "Dwgs.User" user "User.Drawings")
		(19 "Cmts.User" user "User.Comments")
		(21 "Eco1.User" user "User.Eco1")
		(23 "Eco2.User" user "User.Eco2")
		(25 "Edge.Cuts" user "Board Geometry/Outline")
		(27 "Margin" user)
		(31 "F.CrtYd" user "Package Geometry/Place Bound Top")
		(29 "B.CrtYd" user "Package Geometry/Place Bound Bottom")
		(35 "F.Fab" user "Ref Des/Assembly Top")
		(33 "B.Fab" user "Ref Des/Assembly Bottom")
	)
	(footprint ""
		(layer "F.Cu")
		(at 168.449498 -353.36353 -90)
		(property "Reference" "PC1242_P1_1"
			(at 0 0 270)
			(layer "F.SilkS")
			(hide yes)
			(effects
				(font
					(size 1.27 1.27)
				)
			)
		)
		(property "Value" ""
			(at 0 0 270)
			(layer "F.Fab")
			(effects
				(font
					(size 1.27 1.27)
				)
			)
		)
		(duplicate_pad_numbers_are_jumpers no)
		(fp_line
			(start -0.7874 0.4064)
			(end -0.7874 -0.4064)
			(stroke
				(width 0.1524)
				(type default)
			)
			(layer "F.SilkS")
		)
		(fp_line
			(start 0.7874 0.4064)
			(end -0.7874 0.4064)
			(stroke
				(width 0.1524)
				(type default)
			)
			(layer "F.SilkS")
		)
		(fp_line
			(start -0.7874 -0.4064)
			(end 0.7874 -0.4064)
			(stroke
				(width 0.1524)
				(type default)
			)
			(layer "F.SilkS")
		)
		(fp_line
			(start 0.7874 -0.4064)
			(end 0.7874 0.4064)
			(stroke
				(width 0.1524)
				(type default)
			)
			(layer "F.SilkS")
		)
		(fp_line
			(start -0.67945 0.3048)
			(end -0.67945 -0.305054)
			(stroke
				(width 0.1)
				(type default)
			)
			(layer "F.Fab")
		)
		(fp_line
			(start -0.12065 0.3048)
			(end -0.67945 0.3048)
			(stroke
				(width 0.1)
				(type default)
			)
			(layer "F.Fab")
		)
		(fp_line
			(start 0.120396 0.3048)
			(end 0.120396 0.2794)
			(stroke
				(width 0.1)
				(type default)
			)
			(layer "F.Fab")
		)
		(fp_line
			(start 0.67945 0.3048)
			(end 0.120396 0.3048)
			(stroke
				(width 0.1)
				(type default)
			)
			(layer "F.Fab")
		)
		(fp_line
			(start -0.12065 0.2794)
			(end -0.12065 0.3048)
			(stroke
				(width 0.1)
				(type default)
			)
			(layer "F.Fab")
		)
		(fp_line
			(start 0.120396 0.2794)
			(end -0.12065 0.2794)
			(stroke
				(width 0.1)
				(type default)
			)
			(layer "F.Fab")
		)
		(fp_line
			(start -0.12065 -0.2794)
			(end 0.12065 -0.2794)
			(stroke
				(width 0.1)
				(type default)
			)
			(layer "F.Fab")
		)
		(fp_line
			(start 0.12065 -0.2794)
			(end 0.12065 -0.3048)
			(stroke
				(width 0.1)
				(type default)
			)
			(layer "F.Fab")
		)
		(fp_line
			(start 0.12065 -0.3048)
			(end 0.67945 -0.3048)
			(stroke
				(width 0.1)
				(type default)
			)
			(layer "F.Fab")
		)
		(fp_line
			(start 0.67945 -0.3048)
			(end 0.67945 0.3048)
			(stroke
				(width 0.1)
				(type default)
			)
			(layer "F.Fab")
		)
		(fp_line
			(start -0.67945 -0.305054)
			(end -0.12065 -0.305054)
			(stroke
				(width 0.1)
				(type default)
			)
			(layer "F.Fab")
		)
		(fp_line
			(start -0.12065 -0.305054)
			(end -0.12065 -0.2794)
			(stroke
				(width 0.1)
				(type default)
			)
			(layer "F.Fab")
		)
		(pad "1" smd circle
			(at -0.40005 0 270)
			(size 0 0)
			(layers "F.Cu" "F.Mask" "F.Paste")
			(net "PVCCFA_EHV_FIVRA_CPU1_PVCC1")
		)
		(pad "2" smd circle
			(at 0.40005 0 270)
			(size 0 0)
			(layers "F.Cu" "F.Mask" "F.Paste")
			(net "GND")
		)
	)
	(footprint ""
		(layer "F.Cu")
		(at 193.60388 -107.495848)
		(property "Reference" "R1492"
			(at 0 0 0)
			(layer "F.SilkS")
			(hide yes)
			(effects
				(font
					(size 1.27 1.27)
				)
			)
		)
		(property "Value" ""
			(at 0 0 0)
			(layer "F.Fab")
			(effects
				(font
					(size 1.27 1.27)
				)
			)
		)
		(duplicate_pad_numbers_are_jumpers no)
		(fp_line
			(start -0.7874 -0.4064)
			(end 0.7874 -0.4064)
			(stroke
				(width 0.1524)
				(type default)
			)
			(layer "F.SilkS")
		)
		(fp_line
			(start -0.7874 0.4064)
			(end -0.7874 -0.4064)
			(stroke
				(width 0.1524)
				(type default)
			)
			(layer "F.SilkS")
		)
		(fp_line
			(start 0.7874 -0.4064)
			(end 0.7874 0.4064)
			(stroke
				(width 0.1524)
				(type default)
			)
			(layer "F.SilkS")
		)
		(fp_line
			(start 0.7874 0.4064)
			(end -0.7874 0.4064)
			(stroke
				(width 0.1524)
				(type default)
			)
			(layer "F.SilkS")
		)
		(fp_line
			(start -0.67945 -0.305054)
			(end -0.12065 -0.305054)
			(stroke
				(width 0.1)
				(type default)
			)
			(layer "F.Fab")
		)
		(fp_line
			(start -0.67945 0.3048)
			(end -0.67945 -0.305054)
			(stroke
				(width 0.1)
				(type default)
			)
			(layer "F.Fab")
		)
		(fp_line
			(start -0.12065 -0.305054)
			(end -0.12065 -0.2794)
			(stroke
				(width 0.1)
				(type default)
			)
			(layer "F.Fab")
		)
		(fp_line
			(start -0.12065 -0.2794)
			(end 0.12065 -0.2794)
			(stroke
				(width 0.1)
				(type default)
			)
			(layer "F.Fab")
		)
		(fp_line
			(start -0.12065 0.2794)
			(end -0.12065 0.3048)
			(stroke
				(width 0.1)
				(type default)
			)
			(layer "F.Fab")
		)
		(fp_line
			(start -0.12065 0.3048)
			(end -0.67945 0.3048)
			(stroke
				(width 0.1)
				(type default)
			)
			(layer "F.Fab")
		)
		(fp_line
			(start 0.120396 0.2794)
			(end -0.12065 0.2794)
			(stroke
				(width 0.1)
				(type default)
			)
			(layer "F.Fab")
		)
		(fp_line
			(start 0.120396 0.3048)
			(end 0.120396 0.2794)
			(stroke
				(width 0.1)
				(type default)
			)
			(layer "F.Fab")
		)
		(fp_line
			(start 0.12065 -0.3048)
			(end 0.67945 -0.3048)
			(stroke
				(width 0.1)
				(type default)
			)
			(layer "F.Fab")
		)
		(fp_line
			(start 0.12065 -0.2794)
			(end 0.12065 -0.3048)
			(stroke
				(width 0.1)
				(type default)
			)
			(layer "F.Fab")
		)
		(fp_line
			(start 0.67945 -0.3048)
			(end 0.67945 0.3048)
			(stroke
				(width 0.1)
				(type default)
			)
			(layer "F.Fab")
		)
		(fp_line
			(start 0.67945 0.3048)
			(end 0.120396 0.3048)
			(stroke
				(width 0.1)
				(type default)
			)
			(layer "F.Fab")
		)
		(pad "1" smd circle
			(at -0.40005 0)
			(size 0 0)
			(layers "F.Cu" "F.Mask" "F.Paste")
			(net "FM_DIS_PS_PWROK_DLY")
		)
		(pad "2" smd circle
			(at 0.40005 0)
			(size 0 0)
			(layers "F.Cu" "F.Mask" "F.Paste")
			(net "P3V3_AUX")
		)
	)
)
